(kicad_pcb
	(version 20260206)
	(generator "pcbnew")
	(generator_version "10.0")
	(general
		(thickness 1.6)
		(legacy_teardrops no)
	)
	(paper "A4")
	(title_block
		(title "peb — Lightning_PEB_BRD.brd")
		(comment 1 "Lightning (Wiwynn / Facebook NVMe JBOF) / footprints 1825-1831 of 2563")
	)
	(layers
		(0 "F.Cu" signal "TOP")
		(4 "In1.Cu" signal "L2GND")
		(6 "In2.Cu" signal "L3")
		(8 "In3.Cu" signal "L4VCC")
		(10 "In4.Cu" signal "L5VCC")
		(12 "In5.Cu" signal "L6")
		(14 "In6.Cu" signal "L7GND")
		(2 "B.Cu" signal "BOTTOM")
		(9 "F.Adhes" user "F.Adhesive")
		(11 "B.Adhes" user "B.Adhesive")
		(13 "F.Paste" user "Package Geometry/Pastemask Top")
		(15 "B.Paste" user "Package Geometry/Pastemask Bottom")
		(5 "F.SilkS" user "Ref Des/Silkscreen Top")
		(7 "B.SilkS" user "Ref Des/Silkscreen Bottom")
		(1 "F.Mask" user "Board Geometry/Soldermask Top")
		(3 "B.Mask" user "Board Geometry/Soldermask Bottom")
		(17 "Dwgs.User" user "User.Drawings")
		(19 "Cmts.User" user "User.Comments")
		(21 "Eco1.User" user "User.Eco1")
		(23 "Eco2.User" user "User.Eco2")
		(25 "Edge.Cuts" user "Board Geometry/Outline")
		(27 "Margin" user)
		(31 "F.CrtYd" user "Package Geometry/Place Bound Top")
		(29 "B.CrtYd" user "Package Geometry/Place Bound Bottom")
		(35 "F.Fab" user "Ref Des/Assembly Top")
		(33 "B.Fab" user "Ref Des/Assembly Bottom")
	)
	(footprint ""
		(layer "B.Cu")
		(at 182.07482 -13.5128 -90)
		(property "Reference" "R2953"
			(at 0 0 90)
			(layer "B.SilkS")
			(hide yes)
			(effects
				(font
					(size 1.27 1.27)
				)
				(justify mirror)
			)
		)
		(property "Value" "0R2J-2-GP"
			(at -0.064008 -3.993896 270)
			(unlocked yes)
			(layer "B.Fab")
			(hide yes)
			(effects
				(font
					(size 1.016 1.016)
					(thickness 0.1524)
				)
				(justify mirror)
			)
		)
		(property "Device Type" "R402H16"
			(at -0.064008 -5.517896 270)
			(unlocked yes)
			(layer "B.Fab")
			(hide yes)
			(effects
				(font
					(size 1.016 1.016)
					(thickness 0.1524)
				)
				(justify mirror)
			)
		)
		(duplicate_pad_numbers_are_jumpers no)
		(fp_line
			(start -0.508 -0.9398)
			(end 0.508 -0.9398)
			(stroke
				(width 0.1524)
				(type default)
			)
			(layer "B.SilkS")
		)
		(fp_line
			(start 0.508 -0.9398)
			(end 0.508 0.9398)
			(stroke
				(width 0.1524)
				(type default)
			)
			(layer "B.SilkS")
		)
		(fp_rect
			(start 0.508 0.9398)
			(end -0.508 -0.9398)
			(stroke
				(width 0)
				(type default)
			)
			(fill no)
			(layer "B.CrtYd")
		)
		(fp_rect
			(start 0.508 0.9398)
			(end -0.508 -0.9398)
			(stroke
				(width 0)
				(type default)
			)
			(fill no)
			(layer "B.Fab")
		)
		(pad "1" smd custom
			(at 0 -0.4445 90)
			(size 0.1397 0.1397)
			(layers "B.Cu" "B.Mask" "B.Paste")
			(net "PCIE_REFCLK_H3_N")
			(options
				(clearance outline)
				(anchor circle)
			)
			(primitives
				(gr_poly
					(pts
						(arc
							(start -0.1778 0.2794)
							(mid -0.249642 0.249642)
							(end -0.2794 0.1778)
						)
						(arc
							(start -0.2794 -0.1778)
							(mid -0.249642 -0.249642)
							(end -0.1778 -0.2794)
						)
						(arc
							(start 0.1778 -0.2794)
							(mid 0.249642 -0.249642)
							(end 0.2794 -0.1778)
						)
						(arc
							(start 0.2794 0.1778)
							(mid 0.249642 0.249642)
							(end 0.1778 0.2794)
						)
					)
					(width 0)
					(fill yes)
				)
			)
		)
		(pad "2" smd custom
			(at 0 0.4445 90)
			(size 0.1397 0.1397)
			(layers "B.Cu" "B.Mask" "B.Paste")
			(net "PCIE_REFCLK_H3_N_R")
			(options
				(clearance outline)
				(anchor circle)
			)
			(primitives
				(gr_poly
					(pts
						(arc
							(start -0.1778 0.2794)
							(mid -0.249642 0.249642)
							(end -0.2794 0.1778)
						)
						(arc
							(start -0.2794 -0.1778)
							(mid -0.249642 -0.249642)
							(end -0.1778 -0.2794)
						)
						(arc
							(start 0.1778 -0.2794)
							(mid 0.249642 -0.249642)
							(end 0.2794 -0.1778)
						)
						(arc
							(start 0.2794 0.1778)
							(mid 0.249642 0.249642)
							(end 0.1778 0.2794)
						)
					)
					(width 0)
					(fill yes)
				)
			)
		)
	)
	(footprint ""
		(layer "B.Cu")
		(at 232.611422 -31.9786)
		(property "Reference" "C478"
			(at 0 0 0)
			(layer "B.SilkS")
			(hide yes)
			(effects
				(font
					(size 1.27 1.27)
				)
				(justify mirror)
			)
		)
		(property "Value" "SCD1U16V1KX-1-GP"
			(at 2.8321 -1.7399 0)
			(unlocked yes)
			(layer "B.Fab")
			(hide yes)
			(effects
				(font
					(size 1.016 1.016)
					(thickness 0.1524)
				)
				(justify mirror)
			)
		)
		(property "Device Type" "C0201H13"
			(at 2.8321 -3.2639 0)
			(unlocked yes)
			(layer "B.Fab")
			(hide yes)
			(effects
				(font
					(size 1.016 1.016)
					(thickness 0.1524)
				)
				(justify mirror)
			)
		)
		(duplicate_pad_numbers_are_jumpers no)
		(fp_rect
			(start 0.2794 0.6477)
			(end -0.2794 -0.6477)
			(stroke
				(width 0)
				(type default)
			)
			(fill no)
			(layer "B.CrtYd")
		)
		(fp_rect
			(start 0.2794 0.6477)
			(end -0.2794 -0.6477)
			(stroke
				(width 0)
				(type default)
			)
			(fill no)
			(layer "B.Fab")
		)
		(pad "1" smd custom
			(at 0 -0.2794 180)
			(size 0.0762 0.0762)
			(layers "B.Cu" "B.Mask" "B.Paste")
			(net "DUT_VDDO")
			(options
				(clearance outline)
				(anchor circle)
			)
			(primitives
				(gr_poly
					(pts
						(arc
							(start 0.1524 0.127)
							(mid 0.137521 0.162921)
							(end 0.1016 0.1778)
						)
						(arc
							(start -0.1016 0.1778)
							(mid -0.137521 0.162921)
							(end -0.1524 0.127)
						)
						(arc
							(start -0.1524 -0.127)
							(mid -0.137521 -0.162921)
							(end -0.1016 -0.1778)
						)
						(arc
							(start 0.1016 -0.1778)
							(mid 0.137521 -0.162921)
							(end 0.1524 -0.127)
						)
					)
					(width 0)
					(fill yes)
				)
			)
		)
		(pad "2" smd custom
			(at 0 0.2794 180)
			(size 0.0762 0.0762)
			(layers "B.Cu" "B.Mask" "B.Paste")
			(net "GND")
			(options
				(clearance outline)
				(anchor circle)
			)
			(primitives
				(gr_poly
					(pts
						(arc
							(start 0.1524 0.127)
							(mid 0.137521 0.162921)
							(end 0.1016 0.1778)
						)
						(arc
							(start -0.1016 0.1778)
							(mid -0.137521 0.162921)
							(end -0.1524 0.127)
						)
						(arc
							(start -0.1524 -0.127)
							(mid -0.137521 -0.162921)
							(end -0.1016 -0.1778)
						)
						(arc
							(start 0.1016 -0.1778)
							(mid 0.137521 -0.162921)
							(end 0.1524 -0.127)
						)
					)
					(width 0)
					(fill yes)
				)
			)
		)
	)
	(footprint ""
		(layer "B.Cu")
		(at 55.118 -136.271 180)
		(property "Reference" "C8081"
			(at 0 0 0)
			(layer "B.SilkS")
			(hide yes)
			(effects
				(font
					(size 1.27 1.27)
				)
				(justify mirror)
			)
		)
		(property "Value" "SCD1U25V2KX-2-GP"
			(at -1.1811 -2.7051 180)
			(unlocked yes)
			(layer "B.Fab")
			(hide yes)
			(effects
				(font
					(size 1.016 1.016)
					(thickness 0.1524)
				)
				(justify mirror)
			)
		)
		(property "Device Type" "C402H22"
			(at -1.1811 -4.2291 180)
			(unlocked yes)
			(layer "B.Fab")
			(hide yes)
			(effects
				(font
					(size 1.016 1.016)
					(thickness 0.1524)
				)
				(justify mirror)
			)
		)
		(duplicate_pad_numbers_are_jumpers no)
		(fp_rect
			(start 0.4318 0.9525)
			(end -0.4318 -0.9525)
			(stroke
				(width 0)
				(type default)
			)
			(fill no)
			(layer "B.CrtYd")
		)
		(fp_rect
			(start 0.4318 0.9525)
			(end -0.4318 -0.9525)
			(stroke
				(width 0)
				(type default)
			)
			(fill no)
			(layer "B.Fab")
		)
		(pad "1" smd custom
			(at 0 -0.4445)
			(size 0.1524 0.1524)
			(layers "B.Cu" "B.Mask" "B.Paste")
			(net "ADC_P0V9_E")
			(options
				(clearance outline)
				(anchor circle)
			)
			(primitives
				(gr_poly
					(pts
						(arc
							(start 0.3048 0.2032)
							(mid 0.275042 0.275042)
							(end 0.2032 0.3048)
						)
						(arc
							(start -0.2032 0.3048)
							(mid -0.275042 0.275042)
							(end -0.3048 0.2032)
						)
						(arc
							(start -0.3048 -0.2032)
							(mid -0.275042 -0.275042)
							(end -0.2032 -0.3048)
						)
						(arc
							(start 0.2032 -0.3048)
							(mid 0.275042 -0.275042)
							(end 0.3048 -0.2032)
						)
					)
					(width 0)
					(fill yes)
				)
			)
		)
		(pad "2" smd custom
			(at 0 0.4445)
			(size 0.1524 0.1524)
			(layers "B.Cu" "B.Mask" "B.Paste")
			(net "GND")
			(options
				(clearance outline)
				(anchor circle)
			)
			(primitives
				(gr_poly
					(pts
						(arc
							(start 0.3048 0.2032)
							(mid 0.275042 0.275042)
							(end 0.2032 0.3048)
						)
						(arc
							(start -0.2032 0.3048)
							(mid -0.275042 0.275042)
							(end -0.3048 0.2032)
						)
						(arc
							(start -0.3048 -0.2032)
							(mid -0.275042 -0.275042)
							(end -0.2032 -0.3048)
						)
						(arc
							(start 0.2032 -0.3048)
							(mid 0.275042 -0.275042)
							(end 0.3048 -0.2032)
						)
					)
					(width 0)
					(fill yes)
				)
			)
		)
	)
	(footprint ""
		(layer "B.Cu")
		(at 242.824 -20.447)
		(property "Reference" "R792"
			(at 0 0 0)
			(layer "B.SilkS")
			(hide yes)
			(effects
				(font
					(size 1.27 1.27)
				)
				(justify mirror)
			)
		)
		(property "Value" "4K7R2F-GP"
			(at -0.064008 -3.993896 0)
			(unlocked yes)
			(layer "B.Fab")
			(hide yes)
			(effects
				(font
					(size 1.016 1.016)
					(thickness 0.1524)
				)
				(justify mirror)
			)
		)
		(property "Device Type" "R402H16"
			(at -0.064008 -5.517896 0)
			(unlocked yes)
			(layer "B.Fab")
			(hide yes)
			(effects
				(font
					(size 1.016 1.016)
					(thickness 0.1524)
				)
				(justify mirror)
			)
		)
		(duplicate_pad_numbers_are_jumpers no)
		(fp_line
			(start -0.508 -0.9398)
			(end 0.508 -0.9398)
			(stroke
				(width 0.1524)
				(type default)
			)
			(layer "B.SilkS")
		)
		(fp_line
			(start 0.508 -0.9398)
			(end 0.508 0.9398)
			(stroke
				(width 0.1524)
				(type default)
			)
			(layer "B.SilkS")
		)
		(fp_rect
			(start 0.508 0.9398)
			(end -0.508 -0.9398)
			(stroke
				(width 0)
				(type default)
			)
			(fill no)
			(layer "B.CrtYd")
		)
		(fp_rect
			(start 0.508 0.9398)
			(end -0.508 -0.9398)
			(stroke
				(width 0)
				(type default)
			)
			(fill no)
			(layer "B.Fab")
		)
		(pad "1" smd custom
			(at 0 -0.4445 180)
			(size 0.1397 0.1397)
			(layers "B.Cu" "B.Mask" "B.Paste")
			(net "BOOTSTRAP0")
			(options
				(clearance outline)
				(anchor circle)
			)
			(primitives
				(gr_poly
					(pts
						(arc
							(start -0.1778 0.2794)
							(mid -0.249642 0.249642)
							(end -0.2794 0.1778)
						)
						(arc
							(start -0.2794 -0.1778)
							(mid -0.249642 -0.249642)
							(end -0.1778 -0.2794)
						)
						(arc
							(start 0.1778 -0.2794)
							(mid 0.249642 -0.249642)
							(end 0.2794 -0.1778)
						)
						(arc
							(start 0.2794 0.1778)
							(mid 0.249642 0.249642)
							(end 0.1778 0.2794)
						)
					)
					(width 0)
					(fill yes)
				)
			)
		)
		(pad "2" smd custom
			(at 0 0.4445 180)
			(size 0.1397 0.1397)
			(layers "B.Cu" "B.Mask" "B.Paste")
			(net "DUT_VDDO")
			(options
				(clearance outline)
				(anchor circle)
			)
			(primitives
				(gr_poly
					(pts
						(arc
							(start -0.1778 0.2794)
							(mid -0.249642 0.249642)
							(end -0.2794 0.1778)
						)
						(arc
							(start -0.2794 -0.1778)
							(mid -0.249642 -0.249642)
							(end -0.1778 -0.2794)
						)
						(arc
							(start 0.1778 -0.2794)
							(mid 0.249642 -0.249642)
							(end 0.2794 -0.1778)
						)
						(arc
							(start 0.2794 0.1778)
							(mid 0.249642 0.249642)
							(end 0.1778 0.2794)
						)
					)
					(width 0)
					(fill yes)
				)
			)
		)
	)
	(footprint ""
		(layer "B.Cu")
		(at 241.0968 -41.995852 -90)
		(property "Reference" "C437"
			(at 0 0 90)
			(layer "B.SilkS")
			(hide yes)
			(effects
				(font
					(size 1.27 1.27)
				)
				(justify mirror)
			)
		)
		(property "Value" "SCD1U16V1KX-1-GP"
			(at 2.8321 -1.7399 270)
			(unlocked yes)
			(layer "B.Fab")
			(hide yes)
			(effects
				(font
					(size 1.016 1.016)
					(thickness 0.1524)
				)
				(justify mirror)
			)
		)
		(property "Device Type" "C0201H13"
			(at 2.8321 -3.2639 270)
			(unlocked yes)
			(layer "B.Fab")
			(hide yes)
			(effects
				(font
					(size 1.016 1.016)
					(thickness 0.1524)
				)
				(justify mirror)
			)
		)
		(duplicate_pad_numbers_are_jumpers no)
		(fp_rect
			(start 0.2794 0.6477)
			(end -0.2794 -0.6477)
			(stroke
				(width 0)
				(type default)
			)
			(fill no)
			(layer "B.CrtYd")
		)
		(fp_rect
			(start 0.2794 0.6477)
			(end -0.2794 -0.6477)
			(stroke
				(width 0)
				(type default)
			)
			(fill no)
			(layer "B.Fab")
		)
		(pad "1" smd custom
			(at 0 -0.2794 90)
			(size 0.0762 0.0762)
			(layers "B.Cu" "B.Mask" "B.Paste")
			(net "DUT_VDD")
			(options
				(clearance outline)
				(anchor circle)
			)
			(primitives
				(gr_poly
					(pts
						(arc
							(start 0.1524 0.127)
							(mid 0.137521 0.162921)
							(end 0.1016 0.1778)
						)
						(arc
							(start -0.1016 0.1778)
							(mid -0.137521 0.162921)
							(end -0.1524 0.127)
						)
						(arc
							(start -0.1524 -0.127)
							(mid -0.137521 -0.162921)
							(end -0.1016 -0.1778)
						)
						(arc
							(start 0.1016 -0.1778)
							(mid 0.137521 -0.162921)
							(end 0.1524 -0.127)
						)
					)
					(width 0)
					(fill yes)
				)
			)
		)
		(pad "2" smd custom
			(at 0 0.2794 90)
			(size 0.0762 0.0762)
			(layers "B.Cu" "B.Mask" "B.Paste")
			(net "GND")
			(options
				(clearance outline)
				(anchor circle)
			)
			(primitives
				(gr_poly
					(pts
						(arc
							(start 0.1524 0.127)
							(mid 0.137521 0.162921)
							(end 0.1016 0.1778)
						)
						(arc
							(start -0.1016 0.1778)
							(mid -0.137521 0.162921)
							(end -0.1524 0.127)
						)
						(arc
							(start -0.1524 -0.127)
							(mid -0.137521 -0.162921)
							(end -0.1016 -0.1778)
						)
						(arc
							(start 0.1016 -0.1778)
							(mid 0.137521 -0.162921)
							(end 0.1524 -0.127)
						)
					)
					(width 0)
					(fill yes)
				)
			)
		)
	)
	(footprint ""
		(layer "B.Cu")
		(at 222.8088 -190.5762)
		(property "Reference" "R9032"
			(at 0 0 0)
			(layer "B.SilkS")
			(hide yes)
			(effects
				(font
					(size 1.27 1.27)
				)
				(justify mirror)
			)
		)
		(property "Value" "4K7R2F-GP"
			(at -0.064008 -3.993896 0)
			(unlocked yes)
			(layer "B.Fab")
			(hide yes)
			(effects
				(font
					(size 1.016 1.016)
					(thickness 0.1524)
				)
				(justify mirror)
			)
		)
		(property "Device Type" "R402H16"
			(at -0.064008 -5.517896 0)
			(unlocked yes)
			(layer "B.Fab")
			(hide yes)
			(effects
				(font
					(size 1.016 1.016)
					(thickness 0.1524)
				)
				(justify mirror)
			)
		)
		(duplicate_pad_numbers_are_jumpers no)
		(fp_line
			(start -0.508 -0.9398)
			(end 0.508 -0.9398)
			(stroke
				(width 0.1524)
				(type default)
			)
			(layer "B.SilkS")
		)
		(fp_line
			(start 0.508 -0.9398)
			(end 0.508 0.9398)
			(stroke
				(width 0.1524)
				(type default)
			)
			(layer "B.SilkS")
		)
		(fp_rect
			(start 0.508 0.9398)
			(end -0.508 -0.9398)
			(stroke
				(width 0)
				(type default)
			)
			(fill no)
			(layer "B.CrtYd")
		)
		(fp_rect
			(start 0.508 0.9398)
			(end -0.508 -0.9398)
			(stroke
				(width 0)
				(type default)
			)
			(fill no)
			(layer "B.Fab")
		)
		(pad "1" smd custom
			(at 0 -0.4445 180)
			(size 0.1397 0.1397)
			(layers "B.Cu" "B.Mask" "B.Paste")
			(net "SSD_PERST#3")
			(options
				(clearance outline)
				(anchor circle)
			)
			(primitives
				(gr_poly
					(pts
						(arc
							(start -0.1778 0.2794)
							(mid -0.249642 0.249642)
							(end -0.2794 0.1778)
						)
						(arc
							(start -0.2794 -0.1778)
							(mid -0.249642 -0.249642)
							(end -0.1778 -0.2794)
						)
						(arc
							(start 0.1778 -0.2794)
							(mid 0.249642 -0.249642)
							(end 0.2794 -0.1778)
						)
						(arc
							(start 0.2794 0.1778)
							(mid 0.249642 0.249642)
							(end 0.1778 0.2794)
						)
					)
					(width 0)
					(fill yes)
				)
			)
		)
		(pad "2" smd custom
			(at 0 0.4445 180)
			(size 0.1397 0.1397)
			(layers "B.Cu" "B.Mask" "B.Paste")
			(net "GND")
			(options
				(clearance outline)
				(anchor circle)
			)
			(primitives
				(gr_poly
					(pts
						(arc
							(start -0.1778 0.2794)
							(mid -0.249642 0.249642)
							(end -0.2794 0.1778)
						)
						(arc
							(start -0.2794 -0.1778)
							(mid -0.249642 -0.249642)
							(end -0.1778 -0.2794)
						)
						(arc
							(start 0.1778 -0.2794)
							(mid 0.249642 -0.249642)
							(end 0.2794 -0.1778)
						)
						(arc
							(start 0.2794 0.1778)
							(mid 0.249642 0.249642)
							(end 0.1778 0.2794)
						)
					)
					(width 0)
					(fill yes)
				)
			)
		)
	)
	(footprint ""
		(layer "B.Cu")
		(at 61.341 -124.46 -90)
		(property "Reference" "R578"
			(at 0 0 90)
			(layer "B.SilkS")
			(hide yes)
			(effects
				(font
					(size 1.27 1.27)
				)
				(justify mirror)
			)
		)
		(property "Value" "4K7R2F-GP"
			(at -0.064008 -3.993896 270)
			(unlocked yes)
			(layer "B.Fab")
			(hide yes)
			(effects
				(font
					(size 1.016 1.016)
					(thickness 0.1524)
				)
				(justify mirror)
			)
		)
		(property "Device Type" "R402H16"
			(at -0.064008 -5.517896 270)
			(unlocked yes)
			(layer "B.Fab")
			(hide yes)
			(effects
				(font
					(size 1.016 1.016)
					(thickness 0.1524)
				)
				(justify mirror)
			)
		)
		(duplicate_pad_numbers_are_jumpers no)
		(fp_line
			(start -0.508 -0.9398)
			(end 0.508 -0.9398)
			(stroke
				(width 0.1524)
				(type default)
			)
			(layer "B.SilkS")
		)
		(fp_line
			(start 0.508 -0.9398)
			(end 0.508 0.9398)
			(stroke
				(width 0.1524)
				(type default)
			)
			(layer "B.SilkS")
		)
		(fp_rect
			(start 0.508 0.9398)
			(end -0.508 -0.9398)
			(stroke
				(width 0)
				(type default)
			)
			(fill no)
			(layer "B.CrtYd")
		)
		(fp_rect
			(start 0.508 0.9398)
			(end -0.508 -0.9398)
			(stroke
				(width 0)
				(type default)
			)
			(fill no)
			(layer "B.Fab")
		)
		(pad "1" smd custom
			(at 0 -0.4445 90)
			(size 0.1397 0.1397)
			(layers "B.Cu" "B.Mask" "B.Paste")
			(net "BMC_I2C6_C_FCB_SDA")
			(options
				(clearance outline)
				(anchor circle)
			)
			(primitives
				(gr_poly
					(pts
						(arc
							(start -0.1778 0.2794)
							(mid -0.249642 0.249642)
							(end -0.2794 0.1778)
						)
						(arc
							(start -0.2794 -0.1778)
							(mid -0.249642 -0.249642)
							(end -0.1778 -0.2794)
						)
						(arc
							(start 0.1778 -0.2794)
							(mid 0.249642 -0.249642)
							(end 0.2794 -0.1778)
						)
						(arc
							(start 0.2794 0.1778)
							(mid 0.249642 0.249642)
							(end 0.1778 0.2794)
						)
					)
					(width 0)
					(fill yes)
				)
			)
		)
		(pad "2" smd custom
			(at 0 0.4445 90)
			(size 0.1397 0.1397)
			(layers "B.Cu" "B.Mask" "B.Paste")
			(net "P3V3_STBY")
			(options
				(clearance outline)
				(anchor circle)
			)
			(primitives
				(gr_poly
					(pts
						(arc
							(start -0.1778 0.2794)
							(mid -0.249642 0.249642)
							(end -0.2794 0.1778)
						)
						(arc
							(start -0.2794 -0.1778)
							(mid -0.249642 -0.249642)
							(end -0.1778 -0.2794)
						)
						(arc
							(start 0.1778 -0.2794)
							(mid 0.249642 -0.249642)
							(end 0.2794 -0.1778)
						)
						(arc
							(start 0.2794 0.1778)
							(mid 0.249642 0.249642)
							(end 0.1778 0.2794)
						)
					)
					(width 0)
					(fill yes)
				)
			)
		)
	)
)
